# S9S_MB_2U (Grand Teton) — schematic parts with pin connectivity, parts 4546–4698 of 6093; source: Cadence DE-HDL packaged netlist (pstxprt.dat, pstxnet.dat, pstchip.dat)

R2796  Q_RES  33.2 1% CHIP  pkg 0402LF  page 245 : 1 = FM_PDB_BUF_EN_R ; 2 = FM_MB_PDB_SMB9_R_EN
R2800  Q_RES  0 5% EMPTY  pkg 0402LF  page 245 : 1 = SMB_FAN_3V3AUX_R_SCL ; 2 = SMB_FAN_3V3AUX_BUF_SCL
R2801  Q_RES  0 5% EMPTY  pkg 0402LF  page 245 : 1 = SMB_FAN_3V3AUX_R_SDA ; 2 = SMB_FAN_3V3AUX_BUF_SDA
R2802  Q_RES  0 5% CHIP  pkg 0402LF  page 245 : 1 = HPDB_HSC_PWRGD_R ; 2 = HPDB_HSC_PWRGD
R2803  Q_RES  0 5% CHIP  pkg 0402LF  page 245 : 1 = FM_FAN_PWR_EN_R ; 2 = FM_FAN_PWR_EN
R2805  Q_RES  4.7K 5% EMPTY  pkg 0402LF  page 245 : 1 = P3V3_AUX ; 2 = SMB_FAN_3V3AUX_BUF_SCL
R2807  Q_RES  4.7K 5% EMPTY  pkg 0402LF  page 245 : 1 = P3V3_AUX ; 2 = SMB_FAN_3V3AUX_BUF_SDA
R2811  Q_RES  33.2 1% CHIP  pkg 0402LF  page 245 : 1 = SMB_FAN_3V3AUX_BUF_SCL ; 2 = SMB_FAN_3V3AUX_BUF_R_SCL
R2812  Q_RES  33.2 1% CHIP  pkg 0402LF  page 245 : 1 = SMB_FAN_3V3AUX_BUF_SDA ; 2 = SMB_FAN_3V3AUX_BUF_R_SDA
R2815  Q_RES  100K 1% EMPTY  pkg 0402LF  page 151 : 1 = P3V3_AUX ; 2 = BMC_MONITER_R
R2820  Q_RES  4.7K 5% EMPTY  pkg 0402LF  page 151 : 1 = P3V3_AUX ; 2 = BMC_MONITER_BUF_R
R2828  Q_RES  100K 1% CHIP  pkg 0402LF  page 148 : 1 = P3V3_AUX ; 2 = RST_BMC_FROM_SWB_N
R2829  Q_RES  100K 1% EMPTY  pkg 0402LF  page 148 : 1 = RST_BMC_FROM_SWB_N ; 2 = GND
R2830  Q_RES  100K 1% CHIP  pkg 0402LF  page 148 : 1 = P3V3_AUX ; 2 = BIC_MONITER
R2831  Q_RES  100K 1% EMPTY  pkg 0402LF  page 148 : 1 = BIC_MONITER ; 2 = GND
R2832  Q_RES  100K 1% CHIP  pkg 0402LF  page 148 : 1 = P3V3_AUX ; 2 = FM_SWB_BIC_READY_N
R2833  Q_RES  100K 1% EMPTY  pkg 0402LF  page 148 : 1 = FM_SWB_BIC_READY_N ; 2 = GND
R2834  Q_RES  4.7K 5% CHIP  pkg 0402LF  page 148 : 1 = P3V3_AUX ; 2 = RST_BMC_FROM_SWB
R2835  Q_RES  4.7K 5% CHIP  pkg 0402LF  page 148 : 1 = P3V3_AUX ; 2 = BIC_MONITER_N
R2836  Q_RES  4.7K 5% CHIP  pkg 0402LF  page 148 : 1 = P3V3_AUX ; 2 = FM_SWB_BIC_READY
R2837  Q_RES  100K 1% EMPTY  pkg 0402LF  page 148 : 1 = P3V3_AUX ; 2 = FM_SWB_PWRGD
R2838  Q_RES  100K 1% CHIP  pkg 0402LF  page 148 : 1 = FM_SWB_PWRGD ; 2 = GND
R2841  Q_RES  4.7K 5% CHIP  pkg 0402LF  page 148 : 1 = P3V3_AUX ; 2 = FM_SWB_PWRGD_N
R2842  Q_RES  4.7K 5% CHIP  pkg 0402LF  page 148 : 1 = P3V3_AUX ; 2 = FM_GPU_PWRGD_N
R2843  Q_RES  4.7K 1% CHIP  pkg 0402LF  page 250 : 1 = P3V3_ADC ; 2 = GND
R2844  Q_RES  33.2 1% CHIP  pkg 0402LF  page 213 : 1 = FM_SWB_BIC_READY_ISO_N ; 2 = FM_SWB_BIC_READY_ISO_R_N
R2845  Q_RES  33.2 1% CHIP  pkg 0402LF  page 213 : 1 = BMC_MONITER ; 2 = BMC_MONITER_R
R2846  Q_RES  33.2 1% CHIP  pkg 0402LF  page 213 : 1 = BIC_MONITER_ISO ; 2 = BIC_MONITER_ISO_R
R2847  Q_RES  33.2 1% CHIP  pkg 0402LF  page 213 : 1 = RST_BMC_FROM_SWB_ISO_N ; 2 = RST_BMC_FROM_SWB_ISO_R_N
R2848  Q_RES  0 5% CHIP  pkg 0402LF  page 227 : 1 = RST_SWB_BIC_N ; 2 = RST_SWB_BIC_R_N
R2893  Q_RES  0 5% EMPTY  pkg 0402LF  page 234 : 1 = SMB_1_BMC_GPU_R_SCL ; 2 = SMB_1_BMC_GPU_BUF_R_SCL
R2894  Q_RES  0 5% EMPTY  pkg 0402LF  page 234 : 1 = SMB_1_BMC_GPU_R_SDA ; 2 = SMB_1_BMC_GPU_BUF_R_SDA
R2897  Q_RES  33.2 1% CHIP  pkg 0402LF  page 234 : 1 = SMB_1_BMC_GPU_BUF_R_SCL ; 2 = SMB_1_BMC_GPU_BUF_SCL
R2898  Q_RES  33.2 1% CHIP  pkg 0402LF  page 234 : 1 = SMB_1_BMC_GPU_BUF_R_SDA ; 2 = SMB_1_BMC_GPU_BUF_SDA
R2899  Q_RES  0 5% CHIP  pkg 0402LF  page 234 : 1 = SMB_BMC_GPU_EN ; 2 = SMB_BMC_GPU_EN_R1
R2900  Q_RES  2K 1% EMPTY  pkg 0402LF  page 250 : 1 = MAX11617_VREF ; 2 = MAX11617_VREF_R
R2905  Q_RES  0 5% CHIP  pkg 0402LF  page 245 : 1 = RST_SMB_SWITCH_N ; 2 = RST_SMB_SWITCH_R_N
R2906  Q_RES  0 5% CHIP  pkg 0402LF  page 245 : 1 = FM_GPU_HSC_EN_BUF_R1 ; 2 = FM_GPU_HSC_EN_BUF
R2907  Q_RES  5.11K 1% CHIP  pkg 0402LF  page 250 : 1 = P3V3_AUX ; 2 = P3V3_AUX_ADC
R2908  Q_RES  5.11K 1% CHIP  pkg 0402LF  page 250 : 1 = P3V3 ; 2 = P3V3_ADC
R2909  Q_RES  4.7K 5% CHIP  pkg 0402LF  page 151 : 1 = P3V3_AUX ; 2 = RST_SWB_BIC_R_N
R2910  Q_RES  100K 1% EMPTY  pkg 0402LF  page 149 : 1 = P3V3_AUX ; 2 = FM_SWB_PWR_EN_R
R2911  Q_RES  4.7K 5% EMPTY  pkg 0402LF  page 151 : 1 = P3V3_AUX ; 2 = RST_SWB_BIC_BUF_R_N
R2912  Q_RES  4.7K 5% EMPTY  pkg 0402LF  page 151 : 1 = P3V3_AUX ; 2 = FM_GPU_PWR_EN_R1
R2914  Q_RES  4.7K 5% EMPTY  pkg 0402LF  page 149 : 1 = P3V3_AUX ; 2 = FM_SWB_PWR_EN_R1_BUF
R2915  Q_RES  4.7K 5% CHIP  pkg 0402LF  page 151 : 1 = BMC_MONITER_R ; 2 = GND
R2916  Q_RES  4.7K 5% EMPTY  pkg 0402LF  page 151 : 1 = RST_SWB_BIC_R_N ; 2 = GND
R2917  Q_RES  49.9 1% CHIP  pkg 0402LF  page 151 : 1 = BMC_MONITER_BUF_R ; 2 = BMC_MONITER_BUF
R2918  Q_RES  4.7K 5% CHIP  pkg 0402LF  page 149 : 1 = FM_SWB_PWR_EN_R ; 2 = GND
R2919  Q_RES  4.7K 5% CHIP  pkg 0402LF  page 148 : 1 = P3V3_AUX ; 2 = RST_BMC_FROM_SWB_ISO_N
R2920  Q_RES  4.7K 5% CHIP  pkg 0402LF  page 148 : 1 = P3V3_AUX ; 2 = BIC_MONITER_ISO
R2921  Q_RES  10K 1% EMPTY  pkg 0402LF  page 227 : 1 = P3V3_AUX ; 2 = RST_SMB_SWITCH_N
R2922  Q_RES  0 5% CHIP  pkg 0402LF  page 227 : 1 = RST_SMB_SWITCH_N ; 2 = PU_RST_SMB_U181_N
R2923  Q_RES  4.7K 5% EMPTY  pkg 0402LF  page 227 : 1 = P3V3_AUX ; 2 = PU_U181_INT
R2924  Q_RES  49.9 1% CHIP  pkg 0402LF  page 151 : 1 = RST_SWB_BIC_BUF_R_N ; 2 = RST_SWB_BIC_BUF_N
R2925  Q_RES  49.9 1% CHIP  pkg 0402LF  page 151 : 1 = FM_GPU_PWR_EN_R1 ; 2 = FM_GPU_PWR_EN_R_BUF
R2926  Q_RES  4.7K 5% CHIP  pkg 0402LF  page 151 : 1 = BMC_MONITER_BUF_R ; 2 = GND
R2927  Q_RES  100K 1% CHIP  pkg 0402LF  page 151 : 1 = RST_SWB_BIC_BUF_R_N ; 2 = GND
R2932  Q_RES  4.7K 5% CHIP  pkg 0402LF  page 149 : 1 = FM_SWB_PWR_EN_R1_BUF ; 2 = GND
R2933  Q_RES  4.7K 5% CHIP  pkg 0402LF  page 148 : 1 = P3V3_AUX ; 2 = FM_SWB_BIC_READY_ISO_N
R2934  Q_RES  4.7K 5% CHIP  pkg 0402LF  page 148 : 1 = P3V3_AUX ; 2 = FM_SWB_PWRGD_ISO
R2935  Q_RES  4.7K 5% CHIP  pkg 0402LF  page 148 : 1 = P3V3_AUX ; 2 = FM_GPU_PWRGD_ISO
R2936  Q_RES  100K 1% EMPTY  pkg 0402LF  page 151 : 1 = P3V3_AUX ; 2 = FM_GPU_PWR_EN_R
R2937  Q_RES  4.7K 5% CHIP  pkg 0402LF  page 151 : 1 = FM_GPU_PWR_EN_R ; 2 = GND
R2939  Q_RES  33.2 1% CHIP  pkg 0402LF  page 213 : 1 = FM_GPU_HSC_EN_R ; 2 = FM_GPU_HSC_EN
R2940  Q_RES  4.7K 5% EMPTY  pkg 0402LF  page 246 : 1 = P3V3_AUX ; 2 = FM_GPU_HSC_EN
R2941  Q_RES  100K 1% CHIP  pkg 0402LF  page 246 : 1 = FM_GPU_HSC_EN ; 2 = GND
R2944  Q_RES  33.2 1% CHIP  pkg 0402LF  page 246 : 1 = FM_GPU_HSC_EN_BUF_R ; 2 = FM_GPU_HSC_EN_BUF
R2946  Q_RES  4.7K 5% EMPTY  pkg 0402LF  page 246 : 1 = P3V3_AUX ; 2 = FM_GPU_HSC_EN_BUF_R
R2948  Q_RES  4.7K 5% EMPTY  pkg 0402LF  page 246 : 1 = FM_GPU_HSC_EN_BUF_R ; 2 = GND
R2950  Q_RES  4.7K 5% EMPTY  pkg 0402LF  page 245 : 1 = P3V3_AUX ; 2 = FM_PDB_BUF_EN_R
R2966  Q_RES  1M 1% CHIP  pkg 0402LF  page 182 : 1 = P3V3_RTC_AUX ; 2 = FM_INTRUDER_HDR_PCH_N
R2967  Q_RES  0 5% CHIP  pkg 0402LF  page 231 : 1 = SMB_PCIE0_3V3AUX_SCL_R3 ; 2 = SMB_SENSOR_M2_P0_3V3AUX_SCL
R2968  Q_RES  0 5% CHIP  pkg 0402LF  page 231 : 1 = SMB_PCIE0_3V3AUX_SDA_R3 ; 2 = SMB_SENSOR_M2_P0_3V3AUX_SDA
R2969  Q_RES  0 5% CHIP  pkg 0402LF  page 128 : 1 = RST_CPU1_DRAM_GH_N ; 2 = RST_CPU1_DRAM_GH_PLD_N
R2971  Q_RES  0 5% CHIP  pkg 0402LF  page 183 : 1 = FM_BIOS_DEBUG_EN_N ; 2 = FM_BIOS_DEBUG_EN_R_N
R2972  Q_RES  10K 1% CHIP  pkg 0402LF  page 195 : 1 = P1V05_PCH_AUX ; 2 = FAB_REV_ID2
R2973  Q_RES  1K 1% EMPTY  pkg 0402LF  page 195 : 1 = FAB_REV_ID2 ; 2 = GND
R2974  Q_RES  10K 1% CHIP  pkg 0402LF  page 195 : 1 = P1V05_PCH_AUX ; 2 = FAB_REV_ID1
R2975  Q_RES  1K 1% EMPTY  pkg 0402LF  page 195 : 1 = FAB_REV_ID1 ; 2 = GND
R2976  Q_RES  10K 1% EMPTY  pkg 0402LF  page 195 : 1 = P1V05_PCH_AUX ; 2 = FM_BOARD_SKU_ID3
R2977  Q_RES  1K 1% CHIP  pkg 0402LF  page 195 : 1 = FM_BOARD_SKU_ID3 ; 2 = GND
R2978  Q_RES  1K 1% EMPTY  pkg 0402LF  page 195 : 1 = FAB_REV_ID0 ; 2 = GND
R2979  Q_RES  10K 1% EMPTY  pkg 0402LF  page 195 : 1 = P1V05_PCH_AUX ; 2 = FM_BOARD_SKU_ID2
R2980  Q_RES  1K 1% CHIP  pkg 0402LF  page 195 : 1 = FM_BOARD_SKU_ID2 ; 2 = GND
R2982  Q_RES  0 5% CHIP  pkg 0402LF  page 227 : 1 = SMB_IOEXP_3V3AUX_SCL ; 2 = SMB_IOEXP_3V3AUX_SCL_R1
R2983  Q_RES  0 5% CHIP  pkg 0402LF  page 227 : 1 = SMB_IOEXP_3V3AUX_SDA ; 2 = SMB_IOEXP_3V3AUX_SDA_R1
R2984  Q_RES  10K 1% CHIP  pkg 0402LF  page 231 : 1 = P3V3_AUX ; 2 = SMB_BMC_SWB_SCL
R2985  Q_RES  10K 1% CHIP  pkg 0402LF  page 231 : 1 = P3V3_AUX ; 2 = SMB_BMC_SWB_SDA
R2986  Q_RES  0 5% EMPTY  pkg 0402LF  page 234 : 1 = SMB_2_BMC_GPU_R_SCL ; 2 = SMB_2_BMC_GPU_BUF_R_SCL
R2987  Q_RES  0 5% EMPTY  pkg 0402LF  page 234 : 1 = SMB_2_BMC_GPU_R_SDA ; 2 = SMB_2_BMC_GPU_BUF_R_SDA
R2990  Q_RES  33.2 1% CHIP  pkg 0402LF  page 234 : 1 = SMB_2_BMC_GPU_BUF_R_SCL ; 2 = SMB_2_BMC_GPU_BUF_SCL
R2991  Q_RES  33.2 1% CHIP  pkg 0402LF  page 234 : 1 = SMB_2_BMC_GPU_BUF_R_SDA ; 2 = SMB_2_BMC_GPU_BUF_SDA
R2992  Q_RES  0 5% CHIP  pkg 0402LF  page 234 : 1 = SMB_BMC_GPU_EN ; 2 = SMB_BMC_GPU_EN_R3
R2994  Q_RES  0 5% CHIP  pkg 0402LF  page 240 : 1 = P3V_BAT_R1 ; 2 = P3V_BAT_R
R2995  Q_RES  33.2 1% CHIP  pkg 0402LF  page 241 : 1 = SMB_SML1_PMBUS_3V3AUX_PCH_SCL ; 2 = SMB_SML1_PMBUS_HSC_SCL_R3
R2996  Q_RES  33.2 1% CHIP  pkg 0402LF  page 241 : 1 = SMB_SML1_PMBUS_3V3AUX_PCH_SDA ; 2 = SMB_SML1_PMBUS_HSC_SDA_R3
R2999  Q_RES  2.2K 5% EMPTY  pkg 0402LF  page 241 : 1 = SMB_2_BMC_GPU_SCL ; 2 = P3V3_AUX
R3004  Q_RES  2.2K 5% EMPTY  pkg 0402LF  page 241 : 1 = SMB_2_BMC_GPU_SDA ; 2 = P3V3_AUX
R3005  Q_RES  18K 1% CHIP  pkg 0402LF  page 250 : 1 = P5V ; 2 = P5V_ADC
R3023  Q_RES  0 5% CHIP  pkg 0402LF  page 117 : 1 = H_CPU_PM_FAST_WAKE_N ; 2 = H_CPU1_PM_FAST_WAKE_N
R3024  Q_RES  240 1% EMPTY  pkg 0402LF  page 119 : 1 = GND ; 2 = PD_EXT_CLK_SEL_CPU1
R3025  Q_RES  1K 1% EMPTY  pkg 0402LF  page 134 : 1 = FM_REMOTE_DEBUG_DET_R ; 2 = GND
R3026  Q_RES  1K 1% CHIP  pkg 0402LF  page 134 : 1 = JTAG_BMC_PCH_TCK ; 2 = GND
R3027  Q_RES  1K 1% CHIP  pkg 0402LF  page 134 : 1 = JTAG_BMC_CPU_TCK ; 2 = GND
R3028  Q_RES  100K 1% EMPTY  pkg 0402LF  page 148 : 1 = FM_SMB_1_ALERT_GPU_N ; 2 = GND
R3029  Q_RES  4.7K 5% CHIP  pkg 0402LF  page 148 : 1 = P3V3_AUX ; 2 = FM_SMB_1_ALERT_GPU
R3030  Q_RES  4.7K 5% CHIP  pkg 0402LF  page 148 : 1 = P3V3_AUX ; 2 = FM_SMB_1_ALERT_GPU_ISO_N
R3032  Q_RES  100K 1% EMPTY  pkg 0402LF  page 148 : 1 = FM_SMB_2_ALERT_GPU_N ; 2 = GND
R3033  Q_RES  0 5% CHIP  pkg 0402LF  page 151 : 1 = UART_BMC_BIC_RX ; 2 = UART_BMC_BIC_R_RX
R3034  Q_RES  4.7K 5% CHIP  pkg 0402LF  page 148 : 1 = P3V3_AUX ; 2 = FM_SMB_2_ALERT_GPU
R3035  Q_RES  4.7K 5% CHIP  pkg 0402LF  page 148 : 1 = P3V3_AUX ; 2 = FM_SMB_2_ALERT_GPU_ISO_N
R3036  Q_RES  33.2 1% CHIP  pkg 0402LF  page 151 : 1 = UART_BMC_BIC_R_BUF_RX ; 2 = UART_BMC_BIC_BUF_RX
R3037  Q_RES  1K 1% EMPTY  pkg 0402LF  page 158 : 1 = P3V3_AUX ; 2 = PD_SMB_OCP1_HP_ADD1
R3038  Q_RES  5.11K 1% CHIP  pkg 0402LF  page 200 : 1 = P3V3_AUX ; 2 = FM_PCH_SPARE0
R3039  Q_RES  1K 1% CHIP  pkg 0402LF  page 201 : 1 = GND ; 2 = PD_ME_RCVR_N
R3040  Q_RES  1K 1% CHIP  pkg 0402LF  page 204 : 1 = P3V3_AUX ; 2 = IRQ_PCH_SCI_WHEA_N
R3041  Q_RES  10K 1% CHIP  pkg 0402LF  page 204 : 1 = P3V3_AUX ; 2 = FM_PCH_GLB_RST_WARN_N
R3042  Q_RES  10K 1% EMPTY  pkg 0402LF  page 204 : 1 = P1V05_PCH_AUX ; 2 = H_CPU_ERR1_PCH_R_N
R3043  Q_RES  33.2 1% CHIP  pkg 0402LF  page 213 : 1 = IRQ_HSC_FAULT_N ; 2 = IRQ_HSC_FAULT_R1_N
R3045  Q_RES  0 5% CHIP  pkg 0402LF  page 215 : 1 = IRQ_UV_DETECT_N ; 2 = IRQ_UV_DETECT_R_N
R3046  Q_RES  0 5% CHIP  pkg 0402LF  page 215 : 1 = FM_UV_ADR_TRIGGER_N ; 2 = FM_UV_ADR_TRIGGER_R_N
R3047  Q_RES  0 5% CHIP  pkg 0402LF  page 214 : 1 = MB0_P12V_STBY_PWRGD ; 2 = PWRGD_PS_PWROK_PLD
R3048  Q_RES  0 5% CHIP  pkg 0402LF  page 214 : 1 = MB0_P12V_STBY_PWRGD ; 2 = PWRGD_PS_PWROK
R3049  Q_RES  0 5% CHIP  pkg 0402LF  page 215 : 1 = IRQ_SML1_PMBUS_ALERT_N ; 2 = IRQ_PSU_ALERT_R_N
R3050  Q_RES  33.2 1% CHIP  pkg 0402LF  page 223 : 1 = RST_RSMRST_PLD_R_N ; 2 = RST_RSMRST_NM_HDR_N
R3051  Q_RES  0 5% CHIP  pkg 0402LF  page 228 : 1 = IRQ_SML1_PMBUS_ALERT_R_N ; 2 = IRQ_SML1_PMBUS_ALERT_N
R3052  Q_RES  33.2 1% CHIP  pkg 0402LF  page 228 : 1 = SMB_HOST_3V3AUX_SCL_R5 ; 2 = SMB_HOST_ME_SCL
R3053  Q_RES  33.2 1% CHIP  pkg 0402LF  page 228 : 1 = SMB_HOST_3V3AUX_SDA_R5 ; 2 = SMB_HOST_ME_SDA
R3054  Q_RES  33.2 1% CHIP  pkg 0402LF  page 228 : 1 = PWRGD_PS_PWROK_ME_CONN ; 2 = PWRGD_PS_PWROK
R3055  Q_RES  1K 1% CHIP  pkg 0402LF  page 239 : 1 = P3V3_AUX ; 2 = PU_GTL2014_BMC_JTAG_DIR_1
R3056  Q_RES  33.2 1% CHIP  pkg 0402LF  page 239 : 1 = JTAG_DBP_BMC_PRDY_R1_N ; 2 = JTAG_DBP_BMC_PRDY_N
R3057  Q_RES  33.2 1% CHIP  pkg 0402LF  page 239 : 1 = JTAG_DBP_BMC_PREQ_R1_N ; 2 = JTAG_BMC_DBP_PREQ_N
R3058  Q_RES  33.2 1% CHIP  pkg 0402LF  page 241 : 1 = SMB_SML0_3V3AUX_SCL ; 2 = SMB_SML0_ME_SCL
R3059  Q_RES  33.2 1% CHIP  pkg 0402LF  page 241 : 1 = SMB_SML0_3V3AUX_SDA ; 2 = SMB_SML0_ME_SDA
R3060  Q_RES  33.2 1% CHIP  pkg 0402LF  page 241 : 1 = SMB_SML1_PMBUS_3V3AUX_PCH_SCL ; 2 = SMB_PMBUS_SML1_ME_SCL
R3061  Q_RES  33.2 1% CHIP  pkg 0402LF  page 241 : 1 = SMB_SML1_PMBUS_3V3AUX_PCH_SDA ; 2 = SMB_PMBUS_SML1_ME_SDA
R3062  Q_RES  2K 1% EMPTY  pkg 0402LF  page 241 : 1 = SMB_HOST_3V3AUX_SDA ; 2 = P3V3_AUX
R3063  Q_RES  33.2 1% CHIP  pkg 0402LF  page 151 : 1 = FM_PDB_BUF_EN_R ; 2 = FM_UART_EN
R3064  Q_RES  0 5% EMPTY  pkg 0402LF  page 197 : 1 = PECI_CPU_GTL ; 2 = PECI_BMC_ME
R3065  Q_RES  33.2 1% CHIP  pkg 0402LF  page 205 : 1 = FM_BIOS_POST_CMPLT_N ; 2 = FM_BIOS_POST_CMPLT_HDR_N
R3066  Q_RES  0 5% CHIP  pkg 0402LF  page 214 : 1 = FM_SMB_1_ALERT_GPU_ISO_N ; 2 = FM_SMB_1_ALERT_GPU_ISO_R_N
R3067  Q_RES  0 5% CHIP  pkg 0402LF  page 214 : 1 = FM_SMB_2_ALERT_GPU_ISO_N ; 2 = FM_SMB_2_ALERT_GPU_ISO_R_N
R3068  Q_RES  130 1% CHIP  pkg 0402LF  page 255 : 1 = LED_PWRGD_PCH_PWROK_R ; 2 = P3V3_AUX
R3069  Q_RES  130 1% CHIP  pkg 0402LF  page 255 : 1 = LED_PWRGD_SYS_PWROK_R ; 2 = P3V3_AUX
R3070  Q_RES  130 1% CHIP  pkg 0402LF  page 255 : 1 = LED_RST_PLTRST_N ; 2 = P3V3_AUX
R3071  Q_RES  130 1% CHIP  pkg 0402LF  page 252 : 1 = LED_PWRGD_P1V8_PCH_AUX ; 2 = P3V3_AUX
R3072  Q_RES  130 1% CHIP  pkg 0402LF  page 252 : 1 = LED_PWRGD_P1V05_PCH_AUX ; 2 = P3V3_AUX
R3073  Q_RES  130 1% CHIP  pkg 0402LF  page 252 : 1 = LED_FM_PCH_SLP_S4_N ; 2 = P3V3_AUX
R3074  Q_RES  130 1% CHIP  pkg 0402LF  page 252 : 1 = LED_RST_RSMRST_PLD_R_N ; 2 = P3V3_AUX
R3075  Q_RES  130 1% CHIP  pkg 0402LF  page 252 : 1 = LED_PWRGD_PS_PWROK_PLD ; 2 = P3V3_AUX
R3078  Q_RES  130 1% CHIP  pkg 0402LF  page 252 : 1 = LED_FM_PCH_SLP_S3_N ; 2 = P3V3_AUX
R3079  Q_RES  130 1% CHIP  pkg 0402LF  page 256 : 1 = LED_RST_PLD_CPU0_DRAM_EF_N ; 2 = P3V3_AUX
